FILE_TYPE = CONNECTIVITY;
{Allegro Design Entry HDL 17.4-2019 S026 (4007227) 1/17/2022}
"PAGE_NUMBER" = 110;
0"NC";
1"GND\g";
2"GND\g";
3"GND\g";
4"GND\g";
5"GND\g";
6"GND\g";
7"GND\g";
8"GND\g";
9"GND\g";
10"GND\g";
11"GND\g";
12"GND\g";
13"GND\g";
14"GND\g";
15"GND\g";
16"GND\g";
17"GND\g";
18"GND\g";
19"GND\g";
20"P3V3_AUX\g";
21"P3V3_AUX\g";
22"P3V3_AUX\g";
23"FM_P2E_FGA";
24"P2E_MB_BMC_RX_BUF_C_DP<0>";
25"P2E_MB_BMC_RX_R1_DN<0>";
26"FM_P2E_EQB0";
27"FM_P2E_EQB1";
28"P2E_MB_BMC_RX_R1_DP<0>";
29"P2E_MB_BMC_RX_BUF_C_DN<0>";
30"FM_P2E_EN_N";
31"FM_P2E_MODE";
32"FM_P2E_MODE";
33"CLK_GEN2_GPU_FPGA_OE_OR_N";
34"CLK_GEN2_GPU_FPGA_OE_OR_N";
35"P2E_MB_BMC_TX_C_R1_DN<0>";
36"P2E_MB_BMC_TX_C_R1_DP<0>";
37"FM_P2E_FGB";
38"FM_P2E_EQA1";
39"FM_P2E_EQA0";
40"FM_P2E_EQB0";
41"FM_P2E_EQB1";
42"P3V3_AUX\g";
43"P3V3_AUX\g";
44"GND\g";
45"P3V3_AUX\g";
46"PU_TEST";
47"FM_P2E_SWA";
48"FM_P2E_EQA1";
49"FM_P2E_EQA0";
50"FM_P2E_SWB";
51"FM_P2E_SWA";
52"FM_P2E_FGB";
53"FM_P2E_FGA";
54"GND\g";
55"P2E_MB_BMC_TX_BUF_DN<0>";
56"P2E_MB_BMC_TX_BUF_DP<0>";
57"FM_P2E_SWB";
58"P3V3_AUX\g";
%"UNIVERSAL_GND"
"1","(2175,650)","0","pure_quanta_power","I1";
;
ROOM"IO_SLOT"
CDS_LIB"pure_quanta_power"
HDL_POWER"GND";
"A"1;
%"UNIVERSAL_GND"
"1","(2375,2375)","0","pure_quanta_power","I10";
;
ROOM"IO_SLOT"
CDS_LIB"pure_quanta_power"
HDL_POWER"GND";
"A"2;
%"UNIVERSAL_GND"
"1","(2850,2375)","0","pure_quanta_power","I11";
;
ROOM"IO_SLOT"
CDS_LIB"pure_quanta_power"
HDL_POWER"GND";
"A"3;
%"Q_RES"
"2","(2850,2700)","0","pure_quanta","I12";
;
LOCATION"R3273"
$SEC"1"
CDS_SEC"1"
ROOM"PCIE REDRIVER BOM1"
VALUE"68K"
TOLERANCE"1%"
WATTAGE"1/16W"
MATERIAL"EMPTY"
PACK_TYPE"0402LF"
CDS_LIB"pure_quanta"
PART_NUMBER"CS36802FB04";
"A"
$PN"1"23;
"B"
$PN"2"3;
%"UNIVERSAL_POWER"
"1","(2375,3550)","0","pure_quanta_power","I13";
;
HDL_POWER"P3V3_AUX"
CDS_LIB"pure_quanta_power";
"A"42;
%"Q_RES"
"2","(2375,3250)","0","pure_quanta","I14";
;
LOCATION"R3269"
$SEC"1"
CDS_SEC"1"
ROOM"PCIE REDRIVER BOM1"
MATERIAL"EMPTY"
PACK_TYPE"0402LF"
TOLERANCE"1%"
VALUE"1K"
WATTAGE"1/16W"
CDS_LIB"pure_quanta"
PART_NUMBER"CS21002FB06";
"A"
$PN"1"42;
"B"
$PN"2"37;
%"UNIVERSAL_GND"
"1","(3025,650)","0","pure_quanta_power","I15";
;
ROOM"IO_SLOT"
CDS_LIB"pure_quanta_power"
HDL_POWER"GND";
"A"4;
%"Q_RES"
"2","(3025,975)","0","pure_quanta","I16";
;
LOCATION"R3274"
$SEC"1"
CDS_SEC"1"
ROOM"PCIE REDRIVER BOM1"
MATERIAL"EMPTY"
PACK_TYPE"0402LF"
VALUE"68K"
WATTAGE"1/16W"
TOLERANCE"1%"
CDS_LIB"pure_quanta"
PART_NUMBER"CS36802FB04";
"A"
$PN"1"39;
"B"
$PN"2"4;
%"UNIVERSAL_GND"
"1","(3425,650)","0","pure_quanta_power","I17";
;
ROOM"IO_SLOT"
CDS_LIB"pure_quanta_power"
HDL_POWER"GND";
"A"5;
%"Q_RES"
"2","(3425,950)","0","pure_quanta","I18";
;
LOCATION"R3278"
$SEC"1"
CDS_SEC"1"
MATERIAL"CHIP"
WATTAGE"1/16W"
VALUE"1K"
PACK_TYPE"0402LF"
ROOM"PCIE REDRIVER BOM1"
TOLERANCE"1%"
CDS_LIB"pure_quanta"
PART_NUMBER"CS21002FB06";
"A"
$PN"1"39;
"B"
$PN"2"5;
%"Q_RES"
"2","(3425,1525)","0","pure_quanta","I19";
;
LOCATION"R3277"
$SEC"1"
CDS_SEC"1"
PACK_TYPE"0402LF"
ROOM"PCIE REDRIVER BOM1"
VALUE"1K"
TOLERANCE"1%"
MATERIAL"EMPTY"
WATTAGE"1/16W"
CDS_LIB"pure_quanta"
PART_NUMBER"CS21002FB06";
"A"
$PN"1"45;
"B"
$PN"2"39;
%"Q_RES"
"2","(2175,1000)","0","pure_quanta","I2";
;
LOCATION"R3268"
$SEC"1"
CDS_SEC"1"
ROOM"PCIE REDRIVER BOM1"
WATTAGE"1/16W"
TOLERANCE"1%"
VALUE"68K"
PACK_TYPE"0402LF"
MATERIAL"EMPTY"
CDS_LIB"pure_quanta"
PART_NUMBER"CS36802FB04";
"A"
$PN"1"38;
"B"
$PN"2"1;
%"Q_RES"
"2","(4425,975)","0","pure_quanta","I22";
;
LOCATION"R3279"
$SEC"1"
CDS_SEC"1"
MATERIAL"EMPTY"
VALUE"68K"
TOLERANCE"1%"
PACK_TYPE"0402LF"
WATTAGE"1/16W"
ROOM"PCIE REDRIVER BOM1"
CDS_LIB"pure_quanta"
PART_NUMBER"CS36802FB04";
"A"
$PN"1"41;
"B"
$PN"2"6;
%"UNIVERSAL_GND"
"1","(4425,625)","0","pure_quanta_power","I23";
;
ROOM"IO_SLOT"
CDS_LIB"pure_quanta_power"
HDL_POWER"GND";
"A"6;
%"UNIVERSAL_GND"
"1","(4800,625)","0","pure_quanta_power","I24";
;
ROOM"IO_SLOT"
CDS_LIB"pure_quanta_power"
HDL_POWER"GND";
"A"7;
%"Q_RES"
"2","(4800,975)","0","pure_quanta","I25";
;
LOCATION"R3281"
$SEC"1"
CDS_SEC"1"
ROOM"PCIE REDRIVER BOM1"
VALUE"1K"
TOLERANCE"1%"
PACK_TYPE"0402LF"
WATTAGE"1/16W"
MATERIAL"EMPTY"
CDS_LIB"pure_quanta"
PART_NUMBER"CS21002FB06";
"A"
$PN"1"41;
"B"
$PN"2"7;
%"Q_RES"
"2","(4800,1500)","0","pure_quanta","I26";
;
LOCATION"R3280"
$SEC"1"
CDS_SEC"1"
WATTAGE"1/16W"
MATERIAL"EMPTY"
VALUE"1K"
ROOM"PCIE REDRIVER BOM1"
PACK_TYPE"0402LF"
TOLERANCE"1%"
CDS_LIB"pure_quanta"
PART_NUMBER"CS21002FB06";
"A"
$PN"1"43;
"B"
$PN"2"41;
%"UNIVERSAL_POWER"
"1","(4800,1800)","0","pure_quanta_power","I27";
;
HDL_POWER"P3V3_AUX"
CDS_LIB"pure_quanta_power";
"A"43;
%"UNIVERSAL_GND"
"1","(3250,2375)","0","pure_quanta_power","I28";
;
ROOM"IO_SLOT"
CDS_LIB"pure_quanta_power"
HDL_POWER"GND";
"A"8;
%"Q_RES"
"2","(3250,2675)","0","pure_quanta","I29";
;
LOCATION"R3276"
$SEC"1"
CDS_SEC"1"
ROOM"PCIE REDRIVER BOM1"
MATERIAL"EMPTY"
WATTAGE"1/16W"
VALUE"1K"
TOLERANCE"1%"
PACK_TYPE"0402LF"
CDS_LIB"pure_quanta"
PART_NUMBER"CS21002FB06";
"A"
$PN"1"23;
"B"
$PN"2"8;
%"UNIVERSAL_GND"
"1","(2550,650)","0","pure_quanta_power","I3";
;
ROOM"IO_SLOT"
CDS_LIB"pure_quanta_power"
HDL_POWER"GND";
"A"9;
%"Q_RES"
"2","(3250,3250)","0","pure_quanta","I32";
;
LOCATION"R3275"
$SEC"1"
CDS_SEC"1"
ROOM"PCIE REDRIVER BOM1"
VALUE"1K"
TOLERANCE"1%"
MATERIAL"EMPTY"
WATTAGE"1/16W"
PACK_TYPE"0402LF"
CDS_LIB"pure_quanta"
PART_NUMBER"CS21002FB06";
"A"
$PN"1"42;
"B"
$PN"2"23;
%"UNIVERSAL_GND"
"1","(5275,625)","0","pure_quanta_power","I33";
;
ROOM"IO_SLOT"
CDS_LIB"pure_quanta_power"
HDL_POWER"GND";
"A"10;
%"Q_RES"
"2","(5275,950)","0","pure_quanta","I34";
;
LOCATION"R3282"
$SEC"1"
CDS_SEC"1"
ROOM"PCIE REDRIVER BOM1"
TOLERANCE"1%"
VALUE"68K"
PACK_TYPE"0402LF"
WATTAGE"1/16W"
MATERIAL"EMPTY"
CDS_LIB"pure_quanta"
PART_NUMBER"CS36802FB04";
"A"
$PN"1"40;
"B"
$PN"2"10;
%"UNIVERSAL_GND"
"1","(5675,625)","0","pure_quanta_power","I35";
;
ROOM"IO_SLOT"
CDS_LIB"pure_quanta_power"
HDL_POWER"GND";
"A"11;
%"Q_RES"
"2","(5675,925)","0","pure_quanta","I36";
;
LOCATION"R3284"
$SEC"1"
CDS_SEC"1"
ROOM"PCIE REDRIVER BOM1"
WATTAGE"1/16W"
MATERIAL"CHIP"
TOLERANCE"1%"
VALUE"1K"
PACK_TYPE"0402LF"
CDS_LIB"pure_quanta"
PART_NUMBER"CS21002FB06";
"A"
$PN"1"40;
"B"
$PN"2"11;
%"Q_RES"
"2","(5675,1500)","0","pure_quanta","I37";
;
LOCATION"R3283"
$SEC"1"
CDS_SEC"1"
ROOM"PCIE REDRIVER BOM1"
PACK_TYPE"0402LF"
TOLERANCE"1%"
VALUE"1K"
WATTAGE"1/16W"
MATERIAL"EMPTY"
CDS_LIB"pure_quanta"
PART_NUMBER"CS21002FB06";
"A"
$PN"1"43;
"B"
$PN"2"40;
%"Q_RES"
"2","(2550,1000)","0","pure_quanta","I4";
;
LOCATION"R3272"
$SEC"1"
CDS_SEC"1"
ROOM"PCIE REDRIVER BOM1"
VALUE"1K"
TOLERANCE"1%"
PACK_TYPE"0402LF"
WATTAGE"1/16W"
MATERIAL"EMPTY"
CDS_LIB"pure_quanta"
PART_NUMBER"CS21002FB06";
"A"
$PN"1"38;
"B"
$PN"2"9;
%"UNIVERSAL_GND"
"1","(5725,4150)","0","pure_quanta_power","I40";
;
CDS_LIB"pure_quanta_power"
HDL_POWER"GND";
"A"44;
%"UNIVERSAL_GND"
"1","(6450,2375)","0","pure_quanta_power","I41";
;
ROOM"IO_SLOT"
CDS_LIB"pure_quanta_power"
HDL_POWER"GND";
"A"12;
%"Q_RES"
"2","(6450,2725)","0","pure_quanta","I42";
;
LOCATION"R3285"
$SEC"1"
CDS_SEC"1"
WATTAGE"1/16W"
MATERIAL"EMPTY"
PACK_TYPE"0402LF"
TOLERANCE"1%"
VALUE"68K"
ROOM"PCIE REDRIVER BOM1"
CDS_LIB"pure_quanta"
PART_NUMBER"CS36802FB04";
"A"
$PN"1"57;
"B"
$PN"2"12;
%"UNIVERSAL_GND"
"1","(6825,2375)","0","pure_quanta_power","I43";
;
ROOM"IO_SLOT"
CDS_LIB"pure_quanta_power"
HDL_POWER"GND";
"A"13;
%"Q_RES"
"2","(6825,2725)","0","pure_quanta","I44";
;
LOCATION"R3287"
$SEC"1"
CDS_SEC"1"
ROOM"PCIE REDRIVER BOM1"
WATTAGE"1/16W"
PACK_TYPE"0402LF"
MATERIAL"EMPTY"
TOLERANCE"1%"
VALUE"1K"
CDS_LIB"pure_quanta"
PART_NUMBER"CS21002FB06";
"A"
$PN"1"57;
"B"
$PN"2"13;
%"Q_RES"
"2","(6825,3250)","0","pure_quanta","I45";
;
LOCATION"R3286"
$SEC"1"
CDS_SEC"1"
MATERIAL"EMPTY"
ROOM"PCIE REDRIVER BOM1"
TOLERANCE"1%"
VALUE"1K"
WATTAGE"1/16W"
PACK_TYPE"0402LF"
CDS_LIB"pure_quanta"
PART_NUMBER"CS21002FB06";
"A"
$PN"1"58;
"B"
$PN"2"57;
%"UNIVERSAL_POWER"
"1","(6825,3550)","0","pure_quanta_power","I46";
;
HDL_POWER"P3V3_AUX"
CDS_LIB"pure_quanta_power";
"A"58;
%"Q_RES"
"2","(2550,1525)","0","pure_quanta","I5";
;
LOCATION"R3271"
$SEC"1"
CDS_SEC"1"
MATERIAL"EMPTY"
WATTAGE"1/16W"
TOLERANCE"1%"
VALUE"1K"
PACK_TYPE"0402LF"
ROOM"PCIE REDRIVER BOM1"
CDS_LIB"pure_quanta"
PART_NUMBER"CS21002FB06";
"A"
$PN"1"45;
"B"
$PN"2"38;
%"UNIVERSAL_GND"
"1","(2700,5550)","0","pure_quanta_power","I59";
;
CDS_LIB"pure_quanta_power"
HDL_POWER"GND";
"A"54;
%"UNIVERSAL_POWER"
"1","(2550,1825)","0","pure_quanta_power","I6";
;
HDL_POWER"P3V3_AUX"
CDS_LIB"pure_quanta_power";
"A"45;
%"Q_CAP"
"1","(2275,5875)","0","pure_quanta","I60";
;
LOCATION"C1867"
$SEC"1"
CDS_SEC"1"
TOLERANCE"10%"
MATERIAL"X6S"
VOLTAGE"25V"
VALUE"10UF"
PACK_TYPE"C0805"
ROOM"PCIE REDRIVER BOM1"
CDS_LIB"pure_quanta"
PART_NUMBER"CH6104KEA00";
"B"
$PN"2"54;
"A"
$PN"1"22;
%"Q_CAP"
"1","(2825,5875)","0","pure_quanta","I61";
;
LOCATION"C1863"
$SEC"1"
CDS_SEC"1"
VALUE"0.1UF"
TOLERANCE"10%"
VOLTAGE"25V"
PACK_TYPE"0402"
MATERIAL"X7R"
ROOM"PCIE REDRIVER BOM1"
CDS_LIB"pure_quanta"
PART_NUMBER"CH4104K1B00";
"B"
$PN"2"54;
"A"
$PN"1"22;
%"Q_CAP"
"1","(3275,5875)","0","pure_quanta","I62";
;
LOCATION"C1864"
$SEC"1"
CDS_SEC"1"
TOLERANCE"10%"
PACK_TYPE"0402"
MATERIAL"X7R"
VALUE"0.1UF"
VOLTAGE"25V"
ROOM"PCIE REDRIVER BOM1"
CDS_LIB"pure_quanta"
PART_NUMBER"CH4104K1B00";
"B"
$PN"2"54;
"A"
$PN"1"22;
%"PI3EQX12902AZLEX"
"1","(5200,5050)","0","pure_quanta","I63";
;
LOCATION"U237"
$SEC"1"
CDS_SEC"1"
MATERIAL"IC"
PART_TYPE"SMLF"
VALUE"PI3EQX12902AZLEX"
ROOM"PCIE REDRIVER BOM1"
NEEDS_NO_SIZE"TRUE"
CDS_LMAN_SYM_OUTLINE"-300,775,300,-775"
CDS_LIB"pure_quanta"
PART_NUMBER"AL012902001";
"GND_TH"
$PN"TH"44;
"MODE"
$PN"30"31;
"SWA"
$PN"29"51;
"GND7"
$PN"28"44;
"FGA"
$PN"27"53;
"EQA1"
$PN"26"48;
"VDD4"
$PN"25"22;
"AOP"
$PN"24"56;
"AON"
$PN"23"55;
"GND6"
$PN"22"44;
"EQA0"
$PN"21"49;
"EQB0"
$PN"20"26;
"GND5"
$PN"19"44;
"BIN"
$PN"18"25;
"BIP"
$PN"17"28;
"VDD3"
$PN"16"22;
"EQB1"
$PN"15"27;
"FGB"
$PN"14"52;
"GND4"
$PN"13"44;
"SWB"
$PN"12"50;
"EN# \B"
$PN"11"30;
"VDD2"
$PN"10"22;
"BOP"
$PN"9"24;
"BON"
$PN"8"29;
"GND3"
$PN"7"44;
"GND2"
$PN"6"44;
"TEST# \B"
$PN"5"46;
"GND1"
$PN"4"44;
"AIN"
$PN"3"35;
"AIP"
$PN"2"36;
"VDD1"
$PN"1"22;
%"Q_CAP"
"1","(3750,5875)","0","pure_quanta","I64";
;
LOCATION"C1865"
$SEC"1"
CDS_SEC"1"
VALUE"0.1UF"
VOLTAGE"25V"
TOLERANCE"10%"
MATERIAL"X7R"
ROOM"PCIE REDRIVER BOM1"
PACK_TYPE"0402"
CDS_LIB"pure_quanta"
PART_NUMBER"CH4104K1B00";
"B"
$PN"2"54;
"A"
$PN"1"22;
%"Q_CAP"
"1","(4225,5875)","0","pure_quanta","I65";
;
LOCATION"C1866"
$SEC"1"
CDS_SEC"1"
MATERIAL"X7R"
VALUE"0.1UF"
PACK_TYPE"0402"
ROOM"PCIE REDRIVER BOM1"
VOLTAGE"25V"
TOLERANCE"10%"
CDS_LIB"pure_quanta"
PART_NUMBER"CH4104K1B00";
"B"
$PN"2"54;
"A"
$PN"1"22;
%"UNIVERSAL_POWER"
"1","(4625,6275)","0","pure_quanta_power","I66";
;
HDL_POWER"P3V3_AUX"
CDS_LIB"pure_quanta_power";
"A"22;
%"Q_RES"
"1","(6250,5025)","0","pure_quanta","I67";
;
LOCATION"R4537"
$SEC"1"
CDS_SEC"1"
PACK_TYPE"0402LF"
MATERIAL"CHIP"
VALUE"0"
ROOM"PCIE REDRIVER BOM1"
WATTAGE"1/16W"
TOLERANCE"5%"
CDS_LIB"pure_quanta"
PART_NUMBER"CS00002JB13";
"B"
$PN"2"34;
"A"
$PN"1"30;
%"UNIVERSAL_GND"
"1","(2000,2375)","0","pure_quanta_power","I7";
;
ROOM"IO_SLOT"
CDS_LIB"pure_quanta_power"
HDL_POWER"GND";
"A"14;
%"UNIVERSAL_GND"
"1","(7300,2375)","0","pure_quanta_power","I73";
;
ROOM"IO_SLOT"
CDS_LIB"pure_quanta_power"
HDL_POWER"GND";
"A"15;
%"Q_RES"
"2","(7300,2700)","0","pure_quanta","I74";
;
LOCATION"R3288"
$SEC"1"
CDS_SEC"1"
ROOM"PCIE REDRIVER BOM1"
WATTAGE"1/16W"
VALUE"68K"
TOLERANCE"1%"
PACK_TYPE"0402LF"
MATERIAL"EMPTY"
CDS_LIB"pure_quanta"
PART_NUMBER"CS36802FB04";
"A"
$PN"1"47;
"B"
$PN"2"15;
%"UNIVERSAL_GND"
"1","(7700,2375)","0","pure_quanta_power","I75";
;
ROOM"IO_SLOT"
CDS_LIB"pure_quanta_power"
HDL_POWER"GND";
"A"16;
%"Q_RES"
"2","(7700,2675)","0","pure_quanta","I76";
;
LOCATION"R3290"
$SEC"1"
CDS_SEC"1"
VALUE"1K"
ROOM"PCIE REDRIVER BOM1"
WATTAGE"1/16W"
MATERIAL"EMPTY"
PACK_TYPE"0402LF"
TOLERANCE"1%"
CDS_LIB"pure_quanta"
PART_NUMBER"CS21002FB06";
"A"
$PN"1"47;
"B"
$PN"2"16;
%"Q_RES"
"2","(7700,3250)","0","pure_quanta","I77";
;
LOCATION"R3289"
$SEC"1"
CDS_SEC"1"
VALUE"1K"
ROOM"PCIE REDRIVER BOM1"
TOLERANCE"1%"
WATTAGE"1/16W"
MATERIAL"EMPTY"
PACK_TYPE"0402LF"
CDS_LIB"pure_quanta"
PART_NUMBER"CS21002FB06";
"A"
$PN"1"58;
"B"
$PN"2"47;
%"Q_RES"
"2","(2000,2725)","0","pure_quanta","I8";
;
LOCATION"R3267"
$SEC"1"
CDS_SEC"1"
ROOM"PCIE REDRIVER BOM1"
MATERIAL"EMPTY"
WATTAGE"1/16W"
TOLERANCE"1%"
VALUE"68K"
PACK_TYPE"0402LF"
CDS_LIB"pure_quanta"
PART_NUMBER"CS36802FB04";
"A"
$PN"1"37;
"B"
$PN"2"14;
%"UNIVERSAL_GND"
"1","(9575,3700)","0","pure_quanta_power","I80";
;
ROOM"IO_SLOT"
CDS_LIB"pure_quanta_power"
HDL_POWER"GND";
"A"17;
%"Q_RES"
"2","(9575,3925)","0","pure_quanta","I81";
;
LOCATION"R3265"
$SEC"1"
CDS_SEC"1"
MATERIAL"EMPTY"
WATTAGE"1/16W"
VALUE"4.7K"
TOLERANCE"1%"
PACK_TYPE"0402LF"
ROOM"PCIE REDRIVER BOM1"
CDS_LIB"pure_quanta"
PART_NUMBER"CS24702FB06";
"A"
$PN"1"33;
"B"
$PN"2"17;
%"UNIVERSAL_GND"
"1","(8350,4675)","0","pure_quanta_power","I87";
;
ROOM"IO_SLOT"
CDS_LIB"pure_quanta_power"
HDL_POWER"GND";
"A"18;
%"Q_RES"
"2","(8350,4900)","0","pure_quanta","I88";
;
LOCATION"R3291"
$SEC"1"
CDS_SEC"1"
ROOM"PCIE REDRIVER BOM1"
WATTAGE"1/16W"
MATERIAL"EMPTY"
PACK_TYPE"0402LF"
TOLERANCE"1%"
VALUE"4.7K"
CDS_LIB"pure_quanta"
PART_NUMBER"CS24702FB06";
"A"
$PN"1"46;
"B"
$PN"2"18;
%"Q_RES"
"2","(9575,4450)","0","pure_quanta","I89";
;
LOCATION"R3292"
$SEC"1"
CDS_SEC"1"
MATERIAL"CHIP"
VALUE"4.7K"
PACK_TYPE"0402LF"
TOLERANCE"1%"
ROOM"PCIE REDRIVER BOM1"
WATTAGE"1/16W"
CDS_LIB"pure_quanta"
PART_NUMBER"CS24702FB06";
"A"
$PN"1"20;
"B"
$PN"2"33;
%"Q_RES"
"2","(2375,2725)","0","pure_quanta","I9";
;
LOCATION"R3270"
$SEC"1"
CDS_SEC"1"
VALUE"1K"
ROOM"PCIE REDRIVER BOM1"
MATERIAL"EMPTY"
WATTAGE"1/16W"
TOLERANCE"1%"
PACK_TYPE"0402LF"
CDS_LIB"pure_quanta"
PART_NUMBER"CS21002FB06";
"A"
$PN"1"37;
"B"
$PN"2"2;
%"UNIVERSAL_GND"
"1","(9600,5150)","0","pure_quanta_power","I90";
;
ROOM"IO_SLOT"
CDS_LIB"pure_quanta_power"
HDL_POWER"GND";
"A"19;
%"UNIVERSAL_POWER"
"1","(9575,4750)","0","pure_quanta_power","I91";
;
HDL_POWER"P3V3_AUX"
CDS_LIB"pure_quanta_power";
"A"20;
%"Q_RES"
"2","(9600,5375)","0","pure_quanta","I92";
;
LOCATION"R3293"
$SEC"1"
CDS_SEC"1"
MATERIAL"EMPTY"
WATTAGE"1/16W"
TOLERANCE"1%"
VALUE"4.7K"
PACK_TYPE"0402LF"
ROOM"PCIE REDRIVER BOM1"
CDS_LIB"pure_quanta"
PART_NUMBER"CS24702FB06";
"A"
$PN"1"32;
"B"
$PN"2"19;
%"Q_RES"
"2","(9600,5900)","0","pure_quanta","I93";
;
LOCATION"R3266"
$SEC"1"
CDS_SEC"1"
PACK_TYPE"0402LF"
VALUE"4.7K"
MATERIAL"CHIP"
WATTAGE"1/16W"
ROOM"PCIE REDRIVER BOM1"
TOLERANCE"1%"
CDS_LIB"pure_quanta"
PART_NUMBER"CS24702FB06";
"A"
$PN"1"21;
"B"
$PN"2"32;
%"UNIVERSAL_POWER"
"1","(9600,6200)","0","pure_quanta_power","I94";
;
HDL_POWER"P3V3_AUX"
CDS_LIB"pure_quanta_power";
"A"21;
END.
